(kicad_pcb
	(version 20260206)
	(generator "pcbnew")
	(generator_version "10.0")
	(general
		(thickness 1.6)
		(legacy_teardrops no)
	)
	(paper "A4")
	(title_block
		(title "01162023_DA0F0TEBIF0_F0T_Expander_BD_F_brd_V02_OCP.brd")
		(comment 1 "Grand Teton / footprints 3567-3569 of 9728")
	)
	(layers
		(0 "F.Cu" signal "TOP")
		(4 "In1.Cu" signal "GND")
		(6 "In2.Cu" signal "VCC")
		(8 "In3.Cu" signal "VCC1")
		(10 "In4.Cu" signal "GND1")
		(12 "In5.Cu" signal "IN1")
		(14 "In6.Cu" signal "GND2")
		(16 "In7.Cu" signal "IN2")
		(18 "In8.Cu" signal "GND3")
		(20 "In9.Cu" signal "IN3")
		(22 "In10.Cu" signal "GND4")
		(24 "In11.Cu" signal "IN4")
		(26 "In12.Cu" signal "GND5")
		(28 "In13.Cu" signal "IN5")
		(30 "In14.Cu" signal "GND6")
		(32 "In15.Cu" signal "IN6")
		(34 "In16.Cu" signal "GND7")
		(2 "B.Cu" signal "BOTTOM")
		(9 "F.Adhes" user "F.Adhesive")
		(11 "B.Adhes" user "B.Adhesive")
		(13 "F.Paste" user "Package Geometry/Pastemask Top")
		(15 "B.Paste" user "Package Geometry/Pastemask Bottom")
		(5 "F.SilkS" user "Ref Des/Silkscreen Top")
		(7 "B.SilkS" user "Ref Des/Silkscreen Bottom")
		(1 "F.Mask" user "Board Geometry/Soldermask Top")
		(3 "B.Mask" user "Board Geometry/Soldermask Bottom")
		(17 "Dwgs.User" user "User.Drawings")
		(19 "Cmts.User" user "User.Comments")
		(21 "Eco1.User" user "User.Eco1")
		(23 "Eco2.User" user "User.Eco2")
		(25 "Edge.Cuts" user "Board Geometry/Outline")
		(27 "Margin" user)
		(31 "F.CrtYd" user "Package Geometry/Place Bound Top")
		(29 "B.CrtYd" user "Package Geometry/Place Bound Bottom")
		(35 "F.Fab" user "Ref Des/Assembly Top")
		(33 "B.Fab" user "Ref Des/Assembly Bottom")
	)
	(footprint ""
		(layer "F.Cu")
		(at 382.07188 -24.807418)
		(property "Reference" "R450"
			(at 0 0 0)
			(layer "F.SilkS")
			(hide yes)
			(effects
				(font
					(size 1.27 1.27)
				)
			)
		)
		(property "Value" ""
			(at 0 0 0)
			(layer "F.Fab")
			(effects
				(font
					(size 1.27 1.27)
				)
			)
		)
		(duplicate_pad_numbers_are_jumpers no)
		(fp_line
			(start -0.7874 -0.4064)
			(end 0.7874 -0.4064)
			(stroke
				(width 0.1524)
				(type default)
			)
			(layer "F.SilkS")
		)
		(fp_line
			(start -0.7874 0.4064)
			(end -0.7874 -0.4064)
			(stroke
				(width 0.1524)
				(type default)
			)
			(layer "F.SilkS")
		)
		(fp_line
			(start 0.7874 -0.4064)
			(end 0.7874 0.4064)
			(stroke
				(width 0.1524)
				(type default)
			)
			(layer "F.SilkS")
		)
		(fp_line
			(start 0.7874 0.4064)
			(end -0.7874 0.4064)
			(stroke
				(width 0.1524)
				(type default)
			)
			(layer "F.SilkS")
		)
		(fp_line
			(start -0.67945 -0.305054)
			(end -0.12065 -0.305054)
			(stroke
				(width 0.1)
				(type default)
			)
			(layer "F.Fab")
		)
		(fp_line
			(start -0.67945 0.3048)
			(end -0.67945 -0.305054)
			(stroke
				(width 0.1)
				(type default)
			)
			(layer "F.Fab")
		)
		(fp_line
			(start -0.12065 -0.305054)
			(end -0.12065 -0.2794)
			(stroke
				(width 0.1)
				(type default)
			)
			(layer "F.Fab")
		)
		(fp_line
			(start -0.12065 -0.2794)
			(end 0.12065 -0.2794)
			(stroke
				(width 0.1)
				(type default)
			)
			(layer "F.Fab")
		)
		(fp_line
			(start -0.12065 0.2794)
			(end -0.12065 0.3048)
			(stroke
				(width 0.1)
				(type default)
			)
			(layer "F.Fab")
		)
		(fp_line
			(start -0.12065 0.3048)
			(end -0.67945 0.3048)
			(stroke
				(width 0.1)
				(type default)
			)
			(layer "F.Fab")
		)
		(fp_line
			(start 0.120396 0.2794)
			(end -0.12065 0.2794)
			(stroke
				(width 0.1)
				(type default)
			)
			(layer "F.Fab")
		)
		(fp_line
			(start 0.120396 0.3048)
			(end 0.120396 0.2794)
			(stroke
				(width 0.1)
				(type default)
			)
			(layer "F.Fab")
		)
		(fp_line
			(start 0.12065 -0.3048)
			(end 0.67945 -0.3048)
			(stroke
				(width 0.1)
				(type default)
			)
			(layer "F.Fab")
		)
		(fp_line
			(start 0.12065 -0.2794)
			(end 0.12065 -0.3048)
			(stroke
				(width 0.1)
				(type default)
			)
			(layer "F.Fab")
		)
		(fp_line
			(start 0.67945 -0.3048)
			(end 0.67945 0.3048)
			(stroke
				(width 0.1)
				(type default)
			)
			(layer "F.Fab")
		)
		(fp_line
			(start 0.67945 0.3048)
			(end 0.120396 0.3048)
			(stroke
				(width 0.1)
				(type default)
			)
			(layer "F.Fab")
		)
		(pad "1" smd circle
			(at -0.40005 0)
			(size 0 0)
			(layers "F.Cu" "F.Mask" "F.Paste")
			(net "P3V3_SSD13")
		)
		(pad "2" smd circle
			(at 0.40005 0)
			(size 0 0)
			(layers "F.Cu" "F.Mask" "F.Paste")
			(net "PU_CLKREQ13")
		)
	)
	(footprint ""
		(layer "F.Cu")
		(at 148.511514 -280.443432 -90)
		(property "Reference" "R4576"
			(at 0 0 270)
			(layer "F.SilkS")
			(hide yes)
			(effects
				(font
					(size 1.27 1.27)
				)
			)
		)
		(property "Value" ""
			(at 0 0 270)
			(layer "F.Fab")
			(effects
				(font
					(size 1.27 1.27)
				)
			)
		)
		(duplicate_pad_numbers_are_jumpers no)
		(fp_line
			(start -0.7874 0.4064)
			(end -0.7874 -0.4064)
			(stroke
				(width 0.1524)
				(type default)
			)
			(layer "F.SilkS")
		)
		(fp_line
			(start 0.7874 0.4064)
			(end -0.7874 0.4064)
			(stroke
				(width 0.1524)
				(type default)
			)
			(layer "F.SilkS")
		)
		(fp_line
			(start -0.7874 -0.4064)
			(end 0.7874 -0.4064)
			(stroke
				(width 0.1524)
				(type default)
			)
			(layer "F.SilkS")
		)
		(fp_line
			(start 0.7874 -0.4064)
			(end 0.7874 0.4064)
			(stroke
				(width 0.1524)
				(type default)
			)
			(layer "F.SilkS")
		)
		(fp_line
			(start -0.67945 0.3048)
			(end -0.67945 -0.305054)
			(stroke
				(width 0.1)
				(type default)
			)
			(layer "F.Fab")
		)
		(fp_line
			(start -0.12065 0.3048)
			(end -0.67945 0.3048)
			(stroke
				(width 0.1)
				(type default)
			)
			(layer "F.Fab")
		)
		(fp_line
			(start 0.120396 0.3048)
			(end 0.120396 0.2794)
			(stroke
				(width 0.1)
				(type default)
			)
			(layer "F.Fab")
		)
		(fp_line
			(start 0.67945 0.3048)
			(end 0.120396 0.3048)
			(stroke
				(width 0.1)
				(type default)
			)
			(layer "F.Fab")
		)
		(fp_line
			(start -0.12065 0.2794)
			(end -0.12065 0.3048)
			(stroke
				(width 0.1)
				(type default)
			)
			(layer "F.Fab")
		)
		(fp_line
			(start 0.120396 0.2794)
			(end -0.12065 0.2794)
			(stroke
				(width 0.1)
				(type default)
			)
			(layer "F.Fab")
		)
		(fp_line
			(start -0.12065 -0.2794)
			(end 0.12065 -0.2794)
			(stroke
				(width 0.1)
				(type default)
			)
			(layer "F.Fab")
		)
		(fp_line
			(start 0.12065 -0.2794)
			(end 0.12065 -0.3048)
			(stroke
				(width 0.1)
				(type default)
			)
			(layer "F.Fab")
		)
		(fp_line
			(start 0.12065 -0.3048)
			(end 0.67945 -0.3048)
			(stroke
				(width 0.1)
				(type default)
			)
			(layer "F.Fab")
		)
		(fp_line
			(start 0.67945 -0.3048)
			(end 0.67945 0.3048)
			(stroke
				(width 0.1)
				(type default)
			)
			(layer "F.Fab")
		)
		(fp_line
			(start -0.67945 -0.305054)
			(end -0.12065 -0.305054)
			(stroke
				(width 0.1)
				(type default)
			)
			(layer "F.Fab")
		)
		(fp_line
			(start -0.12065 -0.305054)
			(end -0.12065 -0.2794)
			(stroke
				(width 0.1)
				(type default)
			)
			(layer "F.Fab")
		)
		(pad "1" smd circle
			(at -0.40005 0 270)
			(size 0 0)
			(layers "F.Cu" "F.Mask" "F.Paste")
			(net "SYSPLL_VDDA18_PEX1")
		)
		(pad "2" smd circle
			(at 0.40005 0 270)
			(size 0 0)
			(layers "F.Cu" "F.Mask" "F.Paste")
			(net "SYSPLL_VDDA18_PEX1_R")
		)
	)
	(footprint ""
		(layer "F.Cu")
		(at 406.875742 -36.915598 -90)
		(property "Reference" "R5580"
			(at 0 0 270)
			(layer "F.SilkS")
			(hide yes)
			(effects
				(font
					(size 1.27 1.27)
				)
			)
		)
		(property "Value" ""
			(at 0 0 270)
			(layer "F.Fab")
			(effects
				(font
					(size 1.27 1.27)
				)
			)
		)
		(duplicate_pad_numbers_are_jumpers no)
		(fp_line
			(start -0.7874 0.4064)
			(end -0.7874 -0.4064)
			(stroke
				(width 0.1524)
				(type default)
			)
			(layer "F.SilkS")
		)
		(fp_line
			(start 0.7874 0.4064)
			(end -0.7874 0.4064)
			(stroke
				(width 0.1524)
				(type default)
			)
			(layer "F.SilkS")
		)
		(fp_line
			(start -0.7874 -0.4064)
			(end 0.7874 -0.4064)
			(stroke
				(width 0.1524)
				(type default)
			)
			(layer "F.SilkS")
		)
		(fp_line
			(start 0.7874 -0.4064)
			(end 0.7874 0.4064)
			(stroke
				(width 0.1524)
				(type default)
			)
			(layer "F.SilkS")
		)
		(fp_line
			(start -0.67945 0.3048)
			(end -0.67945 -0.305054)
			(stroke
				(width 0.1)
				(type default)
			)
			(layer "F.Fab")
		)
		(fp_line
			(start -0.12065 0.3048)
			(end -0.67945 0.3048)
			(stroke
				(width 0.1)
				(type default)
			)
			(layer "F.Fab")
		)
		(fp_line
			(start 0.120396 0.3048)
			(end 0.120396 0.2794)
			(stroke
				(width 0.1)
				(type default)
			)
			(layer "F.Fab")
		)
		(fp_line
			(start 0.67945 0.3048)
			(end 0.120396 0.3048)
			(stroke
				(width 0.1)
				(type default)
			)
			(layer "F.Fab")
		)
		(fp_line
			(start -0.12065 0.2794)
			(end -0.12065 0.3048)
			(stroke
				(width 0.1)
				(type default)
			)
			(layer "F.Fab")
		)
		(fp_line
			(start 0.120396 0.2794)
			(end -0.12065 0.2794)
			(stroke
				(width 0.1)
				(type default)
			)
			(layer "F.Fab")
		)
		(fp_line
			(start -0.12065 -0.2794)
			(end 0.12065 -0.2794)
			(stroke
				(width 0.1)
				(type default)
			)
			(layer "F.Fab")
		)
		(fp_line
			(start 0.12065 -0.2794)
			(end 0.12065 -0.3048)
			(stroke
				(width 0.1)
				(type default)
			)
			(layer "F.Fab")
		)
		(fp_line
			(start 0.12065 -0.3048)
			(end 0.67945 -0.3048)
			(stroke
				(width 0.1)
				(type default)
			)
			(layer "F.Fab")
		)
		(fp_line
			(start 0.67945 -0.3048)
			(end 0.67945 0.3048)
			(stroke
				(width 0.1)
				(type default)
			)
			(layer "F.Fab")
		)
		(fp_line
			(start -0.67945 -0.305054)
			(end -0.12065 -0.305054)
			(stroke
				(width 0.1)
				(type default)
			)
			(layer "F.Fab")
		)
		(fp_line
			(start -0.12065 -0.305054)
			(end -0.12065 -0.2794)
			(stroke
				(width 0.1)
				(type default)
			)
			(layer "F.Fab")
		)
		(pad "1" smd circle
			(at -0.40005 0 270)
			(size 0 0)
			(layers "F.Cu" "F.Mask" "F.Paste")
			(net "PRSNT_SSD14_R1_N")
		)
		(pad "2" smd circle
			(at 0.40005 0 270)
			(size 0 0)
			(layers "F.Cu" "F.Mask" "F.Paste")
			(net "PRSNT_SSD14_R_N")
		)
	)
)
